(kicad_pcb
	(version 20260206)
	(generator "pcbnew")
	(generator_version "10.0")
	(general
		(thickness 1.6)
		(legacy_teardrops no)
	)
	(paper "A4")
	(title_block
		(title "03242023_DA0F0TMBIJ0_F0T_Motherboard_J_brd_V01_OCP.brd")
		(comment 1 "Grand Teton / footprints 2227-2232 of 6105")
	)
	(layers
		(0 "F.Cu" signal "TOP")
		(4 "In1.Cu" signal "GND")
		(6 "In2.Cu" signal "IN1")
		(8 "In3.Cu" signal "GND1")
		(10 "In4.Cu" signal "IN2")
		(12 "In5.Cu" signal "GND2")
		(14 "In6.Cu" signal "IN3")
		(16 "In7.Cu" signal "GND3")
		(18 "In8.Cu" signal "VCC")
		(20 "In9.Cu" signal "VCC1")
		(22 "In10.Cu" signal "GND4")
		(24 "In11.Cu" signal "IN4")
		(26 "In12.Cu" signal "GND5")
		(28 "In13.Cu" signal "IN5")
		(30 "In14.Cu" signal "GND6")
		(32 "In15.Cu" signal "IN6")
		(34 "In16.Cu" signal "GND7")
		(2 "B.Cu" signal "BOTTOM")
		(9 "F.Adhes" user "F.Adhesive")
		(11 "B.Adhes" user "B.Adhesive")
		(13 "F.Paste" user "Package Geometry/Pastemask Top")
		(15 "B.Paste" user "Package Geometry/Pastemask Bottom")
		(5 "F.SilkS" user "Ref Des/Silkscreen Top")
		(7 "B.SilkS" user "Ref Des/Silkscreen Bottom")
		(1 "F.Mask" user "Board Geometry/Soldermask Top")
		(3 "B.Mask" user "Board Geometry/Soldermask Bottom")
		(17 "Dwgs.User" user "User.Drawings")
		(19 "Cmts.User" user "User.Comments")
		(21 "Eco1.User" user "User.Eco1")
		(23 "Eco2.User" user "User.Eco2")
		(25 "Edge.Cuts" user "Board Geometry/Outline")
		(27 "Margin" user)
		(31 "F.CrtYd" user "Package Geometry/Place Bound Top")
		(29 "B.CrtYd" user "Package Geometry/Place Bound Bottom")
		(35 "F.Fab" user "Ref Des/Assembly Top")
		(33 "B.Fab" user "Ref Des/Assembly Bottom")
	)
	(footprint ""
		(layer "F.Cu")
		(at 430.600104 -135.510778)
		(property "Reference" "R2597"
			(at 0 0 0)
			(layer "F.SilkS")
			(hide yes)
			(effects
				(font
					(size 1.27 1.27)
				)
			)
		)
		(property "Value" ""
			(at 0 0 0)
			(layer "F.Fab")
			(effects
				(font
					(size 1.27 1.27)
				)
			)
		)
		(duplicate_pad_numbers_are_jumpers no)
		(fp_line
			(start -0.7874 -0.4064)
			(end 0.7874 -0.4064)
			(stroke
				(width 0.1524)
				(type default)
			)
			(layer "F.SilkS")
		)
		(fp_line
			(start -0.7874 0.4064)
			(end -0.7874 -0.4064)
			(stroke
				(width 0.1524)
				(type default)
			)
			(layer "F.SilkS")
		)
		(fp_line
			(start 0.7874 -0.4064)
			(end 0.7874 0.4064)
			(stroke
				(width 0.1524)
				(type default)
			)
			(layer "F.SilkS")
		)
		(fp_line
			(start 0.7874 0.4064)
			(end -0.7874 0.4064)
			(stroke
				(width 0.1524)
				(type default)
			)
			(layer "F.SilkS")
		)
		(fp_line
			(start -0.67945 -0.305054)
			(end -0.12065 -0.305054)
			(stroke
				(width 0.1)
				(type default)
			)
			(layer "F.Fab")
		)
		(fp_line
			(start -0.67945 0.3048)
			(end -0.67945 -0.305054)
			(stroke
				(width 0.1)
				(type default)
			)
			(layer "F.Fab")
		)
		(fp_line
			(start -0.12065 -0.305054)
			(end -0.12065 -0.2794)
			(stroke
				(width 0.1)
				(type default)
			)
			(layer "F.Fab")
		)
		(fp_line
			(start -0.12065 -0.2794)
			(end 0.12065 -0.2794)
			(stroke
				(width 0.1)
				(type default)
			)
			(layer "F.Fab")
		)
		(fp_line
			(start -0.12065 0.2794)
			(end -0.12065 0.3048)
			(stroke
				(width 0.1)
				(type default)
			)
			(layer "F.Fab")
		)
		(fp_line
			(start -0.12065 0.3048)
			(end -0.67945 0.3048)
			(stroke
				(width 0.1)
				(type default)
			)
			(layer "F.Fab")
		)
		(fp_line
			(start 0.120396 0.2794)
			(end -0.12065 0.2794)
			(stroke
				(width 0.1)
				(type default)
			)
			(layer "F.Fab")
		)
		(fp_line
			(start 0.120396 0.3048)
			(end 0.120396 0.2794)
			(stroke
				(width 0.1)
				(type default)
			)
			(layer "F.Fab")
		)
		(fp_line
			(start 0.12065 -0.3048)
			(end 0.67945 -0.3048)
			(stroke
				(width 0.1)
				(type default)
			)
			(layer "F.Fab")
		)
		(fp_line
			(start 0.12065 -0.2794)
			(end 0.12065 -0.3048)
			(stroke
				(width 0.1)
				(type default)
			)
			(layer "F.Fab")
		)
		(fp_line
			(start 0.67945 -0.3048)
			(end 0.67945 0.3048)
			(stroke
				(width 0.1)
				(type default)
			)
			(layer "F.Fab")
		)
		(fp_line
			(start 0.67945 0.3048)
			(end 0.120396 0.3048)
			(stroke
				(width 0.1)
				(type default)
			)
			(layer "F.Fab")
		)
		(pad "1" smd circle
			(at -0.40005 0)
			(size 0 0)
			(layers "F.Cu" "F.Mask" "F.Paste")
			(net "IRQ_PVCCFA_CPU0_VRHOT_N")
		)
		(pad "2" smd circle
			(at 0.40005 0)
			(size 0 0)
			(layers "F.Cu" "F.Mask" "F.Paste")
			(net "IRQ_PVCCFA_CPU0_VRHOT_R_N")
		)
	)
	(footprint ""
		(layer "F.Cu")
		(at 495.422936 -427.608238 180)
		(property "Reference" "DB4"
			(at -2.717546 -0.136906 90)
			(unlocked yes)
			(layer "F.SilkS")
			(effects
				(font
					(size 0.7874 0.5842)
					(thickness 0.1524)
				)
				(justify left)
			)
		)
		(property "Value" ""
			(at 0 0 180)
			(layer "F.Fab")
			(effects
				(font
					(size 1.27 1.27)
				)
			)
		)
		(duplicate_pad_numbers_are_jumpers no)
		(fp_line
			(start 3.330702 -4.771136)
			(end 3.21564 -4.46786)
			(stroke
				(width 0.1524)
				(type default)
			)
			(layer "F.SilkS")
		)
		(fp_line
			(start 2.502916 -2.588514)
			(end 0 4.011168)
			(stroke
				(width 0.1524)
				(type default)
			)
			(layer "F.SilkS")
		)
		(fp_line
			(start 0 4.011168)
			(end -3.330702 -4.771136)
			(stroke
				(width 0.1524)
				(type default)
			)
			(layer "F.SilkS")
		)
		(fp_line
			(start -3.330702 -4.771136)
			(end 3.330702 -4.771136)
			(stroke
				(width 0.1524)
				(type default)
			)
			(layer "F.SilkS")
		)
		(fp_line
			(start 3.330702 -4.771136)
			(end 0 4.011168)
			(stroke
				(width 0.1)
				(type default)
			)
			(layer "F.Fab")
		)
		(fp_line
			(start 0 4.011168)
			(end -3.330702 -4.771136)
			(stroke
				(width 0.1)
				(type default)
			)
			(layer "F.Fab")
		)
		(fp_line
			(start -3.330702 -4.771136)
			(end 3.330702 -4.771136)
			(stroke
				(width 0.1)
				(type default)
			)
			(layer "F.Fab")
		)
		(pad "1" thru_hole circle
			(at 0 0 180)
			(size 2.159 2.159)
			(drill 1.7018)
			(layers "*.Cu" "*.Mask")
			(remove_unused_layers no)
			(net "T1_GND")
			(clearance 0.0254)
			(thermal_gap 0.0254)
		)
		(pad "2" thru_hole circle
			(at -1.27 -3.348736 180)
			(size 2.159 2.159)
			(drill 1.7018)
			(layers "*.Cu" "*.Mask")
			(remove_unused_layers no)
			(net "TDR_SE_40_OHM_IN3")
			(clearance 0.0254)
			(thermal_gap 0.0254)
		)
		(pad "3" thru_hole circle
			(at 1.27 -3.348736 180)
			(size 2.159 2.159)
			(drill 1.7018)
			(layers "*.Cu" "*.Mask")
			(remove_unused_layers no)
			(net "TDR_SE_40_OHM_IN3")
			(clearance 0.0254)
			(thermal_gap 0.0254)
		)
	)
	(footprint ""
		(layer "F.Cu")
		(at 392.163808 -38.829742)
		(property "Reference" "C581"
			(at 0 0 0)
			(layer "F.SilkS")
			(hide yes)
			(effects
				(font
					(size 1.27 1.27)
				)
			)
		)
		(property "Value" ""
			(at 0 0 0)
			(layer "F.Fab")
			(effects
				(font
					(size 1.27 1.27)
				)
			)
		)
		(duplicate_pad_numbers_are_jumpers no)
		(fp_line
			(start -0.7874 -0.4064)
			(end 0.7874 -0.4064)
			(stroke
				(width 0.1524)
				(type default)
			)
			(layer "F.SilkS")
		)
		(fp_line
			(start -0.7874 0.4064)
			(end -0.7874 -0.4064)
			(stroke
				(width 0.1524)
				(type default)
			)
			(layer "F.SilkS")
		)
		(fp_line
			(start 0.7874 -0.4064)
			(end 0.7874 0.4064)
			(stroke
				(width 0.1524)
				(type default)
			)
			(layer "F.SilkS")
		)
		(fp_line
			(start 0.7874 0.4064)
			(end -0.7874 0.4064)
			(stroke
				(width 0.1524)
				(type default)
			)
			(layer "F.SilkS")
		)
		(fp_line
			(start -0.67945 -0.305054)
			(end -0.12065 -0.305054)
			(stroke
				(width 0.1)
				(type default)
			)
			(layer "F.Fab")
		)
		(fp_line
			(start -0.67945 0.3048)
			(end -0.67945 -0.305054)
			(stroke
				(width 0.1)
				(type default)
			)
			(layer "F.Fab")
		)
		(fp_line
			(start -0.12065 -0.305054)
			(end -0.12065 -0.2794)
			(stroke
				(width 0.1)
				(type default)
			)
			(layer "F.Fab")
		)
		(fp_line
			(start -0.12065 -0.2794)
			(end 0.12065 -0.2794)
			(stroke
				(width 0.1)
				(type default)
			)
			(layer "F.Fab")
		)
		(fp_line
			(start -0.12065 0.2794)
			(end -0.12065 0.3048)
			(stroke
				(width 0.1)
				(type default)
			)
			(layer "F.Fab")
		)
		(fp_line
			(start -0.12065 0.3048)
			(end -0.67945 0.3048)
			(stroke
				(width 0.1)
				(type default)
			)
			(layer "F.Fab")
		)
		(fp_line
			(start 0.120396 0.2794)
			(end -0.12065 0.2794)
			(stroke
				(width 0.1)
				(type default)
			)
			(layer "F.Fab")
		)
		(fp_line
			(start 0.120396 0.3048)
			(end 0.120396 0.2794)
			(stroke
				(width 0.1)
				(type default)
			)
			(layer "F.Fab")
		)
		(fp_line
			(start 0.12065 -0.3048)
			(end 0.67945 -0.3048)
			(stroke
				(width 0.1)
				(type default)
			)
			(layer "F.Fab")
		)
		(fp_line
			(start 0.12065 -0.2794)
			(end 0.12065 -0.3048)
			(stroke
				(width 0.1)
				(type default)
			)
			(layer "F.Fab")
		)
		(fp_line
			(start 0.67945 -0.3048)
			(end 0.67945 0.3048)
			(stroke
				(width 0.1)
				(type default)
			)
			(layer "F.Fab")
		)
		(fp_line
			(start 0.67945 0.3048)
			(end 0.120396 0.3048)
			(stroke
				(width 0.1)
				(type default)
			)
			(layer "F.Fab")
		)
		(pad "1" smd circle
			(at -0.40005 0)
			(size 0 0)
			(layers "F.Cu" "F.Mask" "F.Paste")
			(net "P3V3_AUX")
		)
		(pad "2" smd circle
			(at 0.40005 0)
			(size 0 0)
			(layers "F.Cu" "F.Mask" "F.Paste")
			(net "GND")
		)
	)
	(footprint ""
		(layer "F.Cu")
		(at 250.53163 -394.17117)
		(property "Reference" "PR2536"
			(at 0 0 0)
			(layer "F.SilkS")
			(hide yes)
			(effects
				(font
					(size 1.27 1.27)
				)
			)
		)
		(property "Value" ""
			(at 0 0 0)
			(layer "F.Fab")
			(effects
				(font
					(size 1.27 1.27)
				)
			)
		)
		(duplicate_pad_numbers_are_jumpers no)
		(fp_line
			(start -0.7874 -0.4064)
			(end 0.7874 -0.4064)
			(stroke
				(width 0.1524)
				(type default)
			)
			(layer "F.SilkS")
		)
		(fp_line
			(start -0.7874 0.4064)
			(end -0.7874 -0.4064)
			(stroke
				(width 0.1524)
				(type default)
			)
			(layer "F.SilkS")
		)
		(fp_line
			(start 0.7874 -0.4064)
			(end 0.7874 0.4064)
			(stroke
				(width 0.1524)
				(type default)
			)
			(layer "F.SilkS")
		)
		(fp_line
			(start 0.7874 0.4064)
			(end -0.7874 0.4064)
			(stroke
				(width 0.1524)
				(type default)
			)
			(layer "F.SilkS")
		)
		(fp_line
			(start -0.67945 -0.305054)
			(end -0.12065 -0.305054)
			(stroke
				(width 0.1)
				(type default)
			)
			(layer "F.Fab")
		)
		(fp_line
			(start -0.67945 0.3048)
			(end -0.67945 -0.305054)
			(stroke
				(width 0.1)
				(type default)
			)
			(layer "F.Fab")
		)
		(fp_line
			(start -0.12065 -0.305054)
			(end -0.12065 -0.2794)
			(stroke
				(width 0.1)
				(type default)
			)
			(layer "F.Fab")
		)
		(fp_line
			(start -0.12065 -0.2794)
			(end 0.12065 -0.2794)
			(stroke
				(width 0.1)
				(type default)
			)
			(layer "F.Fab")
		)
		(fp_line
			(start -0.12065 0.2794)
			(end -0.12065 0.3048)
			(stroke
				(width 0.1)
				(type default)
			)
			(layer "F.Fab")
		)
		(fp_line
			(start -0.12065 0.3048)
			(end -0.67945 0.3048)
			(stroke
				(width 0.1)
				(type default)
			)
			(layer "F.Fab")
		)
		(fp_line
			(start 0.120396 0.2794)
			(end -0.12065 0.2794)
			(stroke
				(width 0.1)
				(type default)
			)
			(layer "F.Fab")
		)
		(fp_line
			(start 0.120396 0.3048)
			(end 0.120396 0.2794)
			(stroke
				(width 0.1)
				(type default)
			)
			(layer "F.Fab")
		)
		(fp_line
			(start 0.12065 -0.3048)
			(end 0.67945 -0.3048)
			(stroke
				(width 0.1)
				(type default)
			)
			(layer "F.Fab")
		)
		(fp_line
			(start 0.12065 -0.2794)
			(end 0.12065 -0.3048)
			(stroke
				(width 0.1)
				(type default)
			)
			(layer "F.Fab")
		)
		(fp_line
			(start 0.67945 -0.3048)
			(end 0.67945 0.3048)
			(stroke
				(width 0.1)
				(type default)
			)
			(layer "F.Fab")
		)
		(fp_line
			(start 0.67945 0.3048)
			(end 0.120396 0.3048)
			(stroke
				(width 0.1)
				(type default)
			)
			(layer "F.Fab")
		)
		(pad "1" smd circle
			(at -0.40005 0)
			(size 0 0)
			(layers "F.Cu" "F.Mask" "F.Paste")
			(net "P12V_HSC_GATE_G6")
		)
		(pad "2" smd circle
			(at 0.40005 0)
			(size 0 0)
			(layers "F.Cu" "F.Mask" "F.Paste")
			(net "P12V_HSC_GATE2")
		)
	)
	(footprint ""
		(layer "F.Cu")
		(at 104.352852 -255.0541 90)
		(property "Reference" "C241"
			(at 0 0 90)
			(layer "F.SilkS")
			(hide yes)
			(effects
				(font
					(size 1.27 1.27)
				)
			)
		)
		(property "Value" ""
			(at 0 0 90)
			(layer "F.Fab")
			(effects
				(font
					(size 1.27 1.27)
				)
			)
		)
		(duplicate_pad_numbers_are_jumpers no)
		(fp_line
			(start 0.7874 -0.4064)
			(end 0.7874 0.4064)
			(stroke
				(width 0.1524)
				(type default)
			)
			(layer "F.SilkS")
		)
		(fp_line
			(start -0.7874 -0.4064)
			(end 0.7874 -0.4064)
			(stroke
				(width 0.1524)
				(type default)
			)
			(layer "F.SilkS")
		)
		(fp_line
			(start 0.7874 0.4064)
			(end -0.7874 0.4064)
			(stroke
				(width 0.1524)
				(type default)
			)
			(layer "F.SilkS")
		)
		(fp_line
			(start -0.7874 0.4064)
			(end -0.7874 -0.4064)
			(stroke
				(width 0.1524)
				(type default)
			)
			(layer "F.SilkS")
		)
		(fp_line
			(start -0.12065 -0.305054)
			(end -0.12065 -0.2794)
			(stroke
				(width 0.1)
				(type default)
			)
			(layer "F.Fab")
		)
		(fp_line
			(start -0.67945 -0.305054)
			(end -0.12065 -0.305054)
			(stroke
				(width 0.1)
				(type default)
			)
			(layer "F.Fab")
		)
		(fp_line
			(start 0.67945 -0.3048)
			(end 0.67945 0.3048)
			(stroke
				(width 0.1)
				(type default)
			)
			(layer "F.Fab")
		)
		(fp_line
			(start 0.12065 -0.3048)
			(end 0.67945 -0.3048)
			(stroke
				(width 0.1)
				(type default)
			)
			(layer "F.Fab")
		)
		(fp_line
			(start 0.12065 -0.2794)
			(end 0.12065 -0.3048)
			(stroke
				(width 0.1)
				(type default)
			)
			(layer "F.Fab")
		)
		(fp_line
			(start -0.12065 -0.2794)
			(end 0.12065 -0.2794)
			(stroke
				(width 0.1)
				(type default)
			)
			(layer "F.Fab")
		)
		(fp_line
			(start 0.120396 0.2794)
			(end -0.12065 0.2794)
			(stroke
				(width 0.1)
				(type default)
			)
			(layer "F.Fab")
		)
		(fp_line
			(start -0.12065 0.2794)
			(end -0.12065 0.3048)
			(stroke
				(width 0.1)
				(type default)
			)
			(layer "F.Fab")
		)
		(fp_line
			(start 0.67945 0.3048)
			(end 0.120396 0.3048)
			(stroke
				(width 0.1)
				(type default)
			)
			(layer "F.Fab")
		)
		(fp_line
			(start 0.120396 0.3048)
			(end 0.120396 0.2794)
			(stroke
				(width 0.1)
				(type default)
			)
			(layer "F.Fab")
		)
		(fp_line
			(start -0.12065 0.3048)
			(end -0.67945 0.3048)
			(stroke
				(width 0.1)
				(type default)
			)
			(layer "F.Fab")
		)
		(fp_line
			(start -0.67945 0.3048)
			(end -0.67945 -0.305054)
			(stroke
				(width 0.1)
				(type default)
			)
			(layer "F.Fab")
		)
		(pad "1" smd circle
			(at -0.40005 0 90)
			(size 0 0)
			(layers "F.Cu" "F.Mask" "F.Paste")
			(net "PVCCIN_CPU1")
		)
		(pad "2" smd circle
			(at 0.40005 0 90)
			(size 0 0)
			(layers "F.Cu" "F.Mask" "F.Paste")
			(net "GND")
		)
	)
	(footprint ""
		(layer "F.Cu")
		(at 179.09032 -409.199588)
		(property "Reference" "R4530"
			(at 0 0 0)
			(layer "F.SilkS")
			(hide yes)
			(effects
				(font
					(size 1.27 1.27)
				)
			)
		)
		(property "Value" ""
			(at 0 0 0)
			(layer "F.Fab")
			(effects
				(font
					(size 1.27 1.27)
				)
			)
		)
		(duplicate_pad_numbers_are_jumpers no)
		(fp_line
			(start -0.7874 -0.4064)
			(end 0.7874 -0.4064)
			(stroke
				(width 0.1524)
				(type default)
			)
			(layer "F.SilkS")
		)
		(fp_line
			(start -0.7874 0.4064)
			(end -0.7874 -0.4064)
			(stroke
				(width 0.1524)
				(type default)
			)
			(layer "F.SilkS")
		)
		(fp_line
			(start 0.7874 -0.4064)
			(end 0.7874 0.4064)
			(stroke
				(width 0.1524)
				(type default)
			)
			(layer "F.SilkS")
		)
		(fp_line
			(start 0.7874 0.4064)
			(end -0.7874 0.4064)
			(stroke
				(width 0.1524)
				(type default)
			)
			(layer "F.SilkS")
		)
		(fp_line
			(start -0.67945 -0.305054)
			(end -0.12065 -0.305054)
			(stroke
				(width 0.1)
				(type default)
			)
			(layer "F.Fab")
		)
		(fp_line
			(start -0.67945 0.3048)
			(end -0.67945 -0.305054)
			(stroke
				(width 0.1)
				(type default)
			)
			(layer "F.Fab")
		)
		(fp_line
			(start -0.12065 -0.305054)
			(end -0.12065 -0.2794)
			(stroke
				(width 0.1)
				(type default)
			)
			(layer "F.Fab")
		)
		(fp_line
			(start -0.12065 -0.2794)
			(end 0.12065 -0.2794)
			(stroke
				(width 0.1)
				(type default)
			)
			(layer "F.Fab")
		)
		(fp_line
			(start -0.12065 0.2794)
			(end -0.12065 0.3048)
			(stroke
				(width 0.1)
				(type default)
			)
			(layer "F.Fab")
		)
		(fp_line
			(start -0.12065 0.3048)
			(end -0.67945 0.3048)
			(stroke
				(width 0.1)
				(type default)
			)
			(layer "F.Fab")
		)
		(fp_line
			(start 0.120396 0.2794)
			(end -0.12065 0.2794)
			(stroke
				(width 0.1)
				(type default)
			)
			(layer "F.Fab")
		)
		(fp_line
			(start 0.120396 0.3048)
			(end 0.120396 0.2794)
			(stroke
				(width 0.1)
				(type default)
			)
			(layer "F.Fab")
		)
		(fp_line
			(start 0.12065 -0.3048)
			(end 0.67945 -0.3048)
			(stroke
				(width 0.1)
				(type default)
			)
			(layer "F.Fab")
		)
		(fp_line
			(start 0.12065 -0.2794)
			(end 0.12065 -0.3048)
			(stroke
				(width 0.1)
				(type default)
			)
			(layer "F.Fab")
		)
		(fp_line
			(start 0.67945 -0.3048)
			(end 0.67945 0.3048)
			(stroke
				(width 0.1)
				(type default)
			)
			(layer "F.Fab")
		)
		(fp_line
			(start 0.67945 0.3048)
			(end 0.120396 0.3048)
			(stroke
				(width 0.1)
				(type default)
			)
			(layer "F.Fab")
		)
		(pad "1" smd circle
			(at -0.40005 0)
			(size 0 0)
			(layers "F.Cu" "F.Mask" "F.Paste")
			(net "SMB_SML1_PMBUS_HSC_SCL_R3")
		)
		(pad "2" smd circle
			(at 0.40005 0)
			(size 0 0)
			(layers "F.Cu" "F.Mask" "F.Paste")
			(net "SMB_SML1_PMBUS_HSC_SCL")
		)
	)
)
